#ISCELL
  pure_quanta quanta_title_block_c *
  *
#ISCELL
  standard offpage *
  page43_i1
#ISCELL
  standard offpage *
  page43_i10
#ISCELL
  standard offpage *
  page43_i11
#CELL
  pure_quanta q_res *
  page43_i12
#CELL
  pure_quanta q_res *
  page43_i13
#ISCELL
  standard offpage *
  page43_i14
#ISCELL
  standard offpage *
  page43_i15
#CELL
  pure_quanta q_res *
  page43_i16
#CELL
  pure_quanta q_res *
  page43_i17
#ISCELL
  standard offpage *
  page43_i2
#ISCELL
  logical_power universal_gnd *
  page43_i20
#ISCELL
  standard offpage *
  page43_i47
#CELL
  pure_quanta q_res *
  page43_i52
#ISCELL
  logical_power universal_gnd *
  page43_i54
#ISCELL
  standard offpage *
  page43_i55
#CELL
  pure_quanta q_res *
  page43_i56
